(kicad_pcb
	(version 20260206)
	(generator "pcbnew")
	(generator_version "10.0")
	(general
		(thickness 1.6)
		(legacy_teardrops no)
	)
	(paper "A4")
	(title_block
		(title "01162023_DA0F0TEBIF0_F0T_Expander_BD_F_brd_V02_OCP.brd")
		(comment 1 "Grand Teton / footprints 9177-9182 of 9728")
	)
	(layers
		(0 "F.Cu" signal "TOP")
		(4 "In1.Cu" signal "GND")
		(6 "In2.Cu" signal "VCC")
		(8 "In3.Cu" signal "VCC1")
		(10 "In4.Cu" signal "GND1")
		(12 "In5.Cu" signal "IN1")
		(14 "In6.Cu" signal "GND2")
		(16 "In7.Cu" signal "IN2")
		(18 "In8.Cu" signal "GND3")
		(20 "In9.Cu" signal "IN3")
		(22 "In10.Cu" signal "GND4")
		(24 "In11.Cu" signal "IN4")
		(26 "In12.Cu" signal "GND5")
		(28 "In13.Cu" signal "IN5")
		(30 "In14.Cu" signal "GND6")
		(32 "In15.Cu" signal "IN6")
		(34 "In16.Cu" signal "GND7")
		(2 "B.Cu" signal "BOTTOM")
		(9 "F.Adhes" user "F.Adhesive")
		(11 "B.Adhes" user "B.Adhesive")
		(13 "F.Paste" user "Package Geometry/Pastemask Top")
		(15 "B.Paste" user "Package Geometry/Pastemask Bottom")
		(5 "F.SilkS" user "Ref Des/Silkscreen Top")
		(7 "B.SilkS" user "Ref Des/Silkscreen Bottom")
		(1 "F.Mask" user "Board Geometry/Soldermask Top")
		(3 "B.Mask" user "Board Geometry/Soldermask Bottom")
		(17 "Dwgs.User" user "User.Drawings")
		(19 "Cmts.User" user "User.Comments")
		(21 "Eco1.User" user "User.Eco1")
		(23 "Eco2.User" user "User.Eco2")
		(25 "Edge.Cuts" user "Board Geometry/Outline")
		(27 "Margin" user)
		(31 "F.CrtYd" user "Package Geometry/Place Bound Top")
		(29 "B.CrtYd" user "Package Geometry/Place Bound Bottom")
		(35 "F.Fab" user "Ref Des/Assembly Top")
		(33 "B.Fab" user "Ref Des/Assembly Bottom")
	)
	(footprint ""
		(layer "B.Cu")
		(at 233.839512 -234.728004 90)
		(property "Reference" "R6184"
			(at 0 0 90)
			(layer "B.SilkS")
			(hide yes)
			(effects
				(font
					(size 1.27 1.27)
				)
				(justify mirror)
			)
		)
		(property "Value" ""
			(at 0 0 90)
			(layer "B.Fab")
			(effects
				(font
					(size 1.27 1.27)
				)
				(justify mirror)
			)
		)
		(duplicate_pad_numbers_are_jumpers no)
		(fp_line
			(start 0.7874 -0.4064)
			(end -0.7874 -0.4064)
			(stroke
				(width 0.1524)
				(type default)
			)
			(layer "B.SilkS")
		)
		(fp_line
			(start -0.7874 -0.4064)
			(end -0.7874 0.4064)
			(stroke
				(width 0.1524)
				(type default)
			)
			(layer "B.SilkS")
		)
		(fp_line
			(start 0.7874 0.4064)
			(end 0.7874 -0.4064)
			(stroke
				(width 0.1524)
				(type default)
			)
			(layer "B.SilkS")
		)
		(fp_line
			(start -0.7874 0.4064)
			(end 0.7874 0.4064)
			(stroke
				(width 0.1524)
				(type default)
			)
			(layer "B.SilkS")
		)
		(fp_line
			(start 0.67945 -0.305054)
			(end 0.12065 -0.305054)
			(stroke
				(width 0.1)
				(type default)
			)
			(layer "B.Fab")
		)
		(fp_line
			(start 0.12065 -0.305054)
			(end 0.12065 -0.2794)
			(stroke
				(width 0.1)
				(type default)
			)
			(layer "B.Fab")
		)
		(fp_line
			(start -0.12065 -0.3048)
			(end -0.67945 -0.3048)
			(stroke
				(width 0.1)
				(type default)
			)
			(layer "B.Fab")
		)
		(fp_line
			(start -0.67945 -0.3048)
			(end -0.67945 0.3048)
			(stroke
				(width 0.1)
				(type default)
			)
			(layer "B.Fab")
		)
		(fp_line
			(start 0.12065 -0.2794)
			(end -0.12065 -0.2794)
			(stroke
				(width 0.1)
				(type default)
			)
			(layer "B.Fab")
		)
		(fp_line
			(start -0.12065 -0.2794)
			(end -0.12065 -0.3048)
			(stroke
				(width 0.1)
				(type default)
			)
			(layer "B.Fab")
		)
		(fp_line
			(start 0.12065 0.2794)
			(end 0.12065 0.3048)
			(stroke
				(width 0.1)
				(type default)
			)
			(layer "B.Fab")
		)
		(fp_line
			(start -0.120396 0.2794)
			(end 0.12065 0.2794)
			(stroke
				(width 0.1)
				(type default)
			)
			(layer "B.Fab")
		)
		(fp_line
			(start 0.67945 0.3048)
			(end 0.67945 -0.305054)
			(stroke
				(width 0.1)
				(type default)
			)
			(layer "B.Fab")
		)
		(fp_line
			(start 0.12065 0.3048)
			(end 0.67945 0.3048)
			(stroke
				(width 0.1)
				(type default)
			)
			(layer "B.Fab")
		)
		(fp_line
			(start -0.120396 0.3048)
			(end -0.120396 0.2794)
			(stroke
				(width 0.1)
				(type default)
			)
			(layer "B.Fab")
		)
		(fp_line
			(start -0.67945 0.3048)
			(end -0.120396 0.3048)
			(stroke
				(width 0.1)
				(type default)
			)
			(layer "B.Fab")
		)
		(pad "1" smd circle
			(at 0.40005 0 270)
			(size 0 0)
			(layers "B.Cu" "B.Mask" "B.Paste")
			(net "GND")
		)
		(pad "2" smd circle
			(at -0.40005 0 270)
			(size 0 0)
			(layers "B.Cu" "B.Mask" "B.Paste")
			(net "SSD2_PWRDIS_BIC_R")
		)
	)
	(footprint ""
		(layer "B.Cu")
		(at 411.750002 -303.499774 -90)
		(property "Reference" "C3439"
			(at 0 0 90)
			(layer "B.SilkS")
			(hide yes)
			(effects
				(font
					(size 1.27 1.27)
				)
				(justify mirror)
			)
		)
		(property "Value" ""
			(at 0 0 90)
			(layer "B.Fab")
			(effects
				(font
					(size 1.27 1.27)
				)
				(justify mirror)
			)
		)
		(duplicate_pad_numbers_are_jumpers no)
		(fp_line
			(start -0.299974 0.150114)
			(end 0.299974 0.150114)
			(stroke
				(width 0.1)
				(type default)
			)
			(layer "B.Fab")
		)
		(fp_line
			(start 0.299974 0.150114)
			(end 0.299974 -0.150114)
			(stroke
				(width 0.1)
				(type default)
			)
			(layer "B.Fab")
		)
		(fp_line
			(start -0.299974 -0.150114)
			(end -0.299974 0.150114)
			(stroke
				(width 0.1)
				(type default)
			)
			(layer "B.Fab")
		)
		(fp_line
			(start 0.299974 -0.150114)
			(end -0.299974 -0.150114)
			(stroke
				(width 0.1)
				(type default)
			)
			(layer "B.Fab")
		)
		(pad "1" smd rect
			(at 0.2667 0 90)
			(size 0.3048 0.381)
			(layers "B.Cu" "B.Mask" "B.Paste")
			(net "P1V25_PEX3")
		)
		(pad "2" smd rect
			(at -0.2667 0 90)
			(size 0.3048 0.381)
			(layers "B.Cu" "B.Mask" "B.Paste")
			(net "GND")
		)
	)
	(footprint ""
		(layer "B.Cu")
		(at 128.454912 -321.813174 -90)
		(property "Reference" "R6476"
			(at 0 0 90)
			(layer "B.SilkS")
			(hide yes)
			(effects
				(font
					(size 1.27 1.27)
				)
				(justify mirror)
			)
		)
		(property "Value" ""
			(at 0 0 90)
			(layer "B.Fab")
			(effects
				(font
					(size 1.27 1.27)
				)
				(justify mirror)
			)
		)
		(duplicate_pad_numbers_are_jumpers no)
		(fp_line
			(start -0.7874 0.4064)
			(end 0.7874 0.4064)
			(stroke
				(width 0.1524)
				(type default)
			)
			(layer "B.SilkS")
		)
		(fp_line
			(start 0.7874 0.4064)
			(end 0.7874 -0.4064)
			(stroke
				(width 0.1524)
				(type default)
			)
			(layer "B.SilkS")
		)
		(fp_line
			(start -0.7874 -0.4064)
			(end -0.7874 0.4064)
			(stroke
				(width 0.1524)
				(type default)
			)
			(layer "B.SilkS")
		)
		(fp_line
			(start 0.7874 -0.4064)
			(end -0.7874 -0.4064)
			(stroke
				(width 0.1524)
				(type default)
			)
			(layer "B.SilkS")
		)
		(fp_line
			(start -0.67945 0.3048)
			(end -0.120396 0.3048)
			(stroke
				(width 0.1)
				(type default)
			)
			(layer "B.Fab")
		)
		(fp_line
			(start -0.120396 0.3048)
			(end -0.120396 0.2794)
			(stroke
				(width 0.1)
				(type default)
			)
			(layer "B.Fab")
		)
		(fp_line
			(start 0.12065 0.3048)
			(end 0.67945 0.3048)
			(stroke
				(width 0.1)
				(type default)
			)
			(layer "B.Fab")
		)
		(fp_line
			(start 0.67945 0.3048)
			(end 0.67945 -0.305054)
			(stroke
				(width 0.1)
				(type default)
			)
			(layer "B.Fab")
		)
		(fp_line
			(start -0.120396 0.2794)
			(end 0.12065 0.2794)
			(stroke
				(width 0.1)
				(type default)
			)
			(layer "B.Fab")
		)
		(fp_line
			(start 0.12065 0.2794)
			(end 0.12065 0.3048)
			(stroke
				(width 0.1)
				(type default)
			)
			(layer "B.Fab")
		)
		(fp_line
			(start -0.12065 -0.2794)
			(end -0.12065 -0.3048)
			(stroke
				(width 0.1)
				(type default)
			)
			(layer "B.Fab")
		)
		(fp_line
			(start 0.12065 -0.2794)
			(end -0.12065 -0.2794)
			(stroke
				(width 0.1)
				(type default)
			)
			(layer "B.Fab")
		)
		(fp_line
			(start -0.67945 -0.3048)
			(end -0.67945 0.3048)
			(stroke
				(width 0.1)
				(type default)
			)
			(layer "B.Fab")
		)
		(fp_line
			(start -0.12065 -0.3048)
			(end -0.67945 -0.3048)
			(stroke
				(width 0.1)
				(type default)
			)
			(layer "B.Fab")
		)
		(fp_line
			(start 0.12065 -0.305054)
			(end 0.12065 -0.2794)
			(stroke
				(width 0.1)
				(type default)
			)
			(layer "B.Fab")
		)
		(fp_line
			(start 0.67945 -0.305054)
			(end 0.12065 -0.305054)
			(stroke
				(width 0.1)
				(type default)
			)
			(layer "B.Fab")
		)
		(pad "1" smd circle
			(at 0.40005 0 90)
			(size 0 0)
			(layers "B.Cu" "B.Mask" "B.Paste")
			(net "P0V8_SERDES_VDDA_PEX1")
		)
		(pad "2" smd circle
			(at -0.40005 0 90)
			(size 0 0)
			(layers "B.Cu" "B.Mask" "B.Paste")
			(net "P0V8_SERDES_VDDA_PEX1_C1")
		)
	)
	(footprint ""
		(layer "B.Cu")
		(at 342.893396 -220.38691 90)
		(property "Reference" "C2074"
			(at 0 0 90)
			(layer "B.SilkS")
			(hide yes)
			(effects
				(font
					(size 1.27 1.27)
				)
				(justify mirror)
			)
		)
		(property "Value" ""
			(at 0 0 90)
			(layer "B.Fab")
			(effects
				(font
					(size 1.27 1.27)
				)
				(justify mirror)
			)
		)
		(duplicate_pad_numbers_are_jumpers no)
		(fp_line
			(start 0.69215 -0.2921)
			(end -0.69215 -0.2921)
			(stroke
				(width 0.1524)
				(type default)
			)
			(layer "B.SilkS")
		)
		(fp_line
			(start -0.69215 -0.2921)
			(end -0.69215 0.2921)
			(stroke
				(width 0.1524)
				(type default)
			)
			(layer "B.SilkS")
		)
		(fp_line
			(start 0.69215 0.2921)
			(end 0.69215 -0.2921)
			(stroke
				(width 0.1524)
				(type default)
			)
			(layer "B.SilkS")
		)
		(fp_line
			(start -0.69215 0.2921)
			(end 0.69215 0.2921)
			(stroke
				(width 0.1524)
				(type default)
			)
			(layer "B.SilkS")
		)
		(fp_line
			(start 0.51435 -0.2794)
			(end -0.51435 -0.2794)
			(stroke
				(width 0.1)
				(type default)
			)
			(layer "B.Fab")
		)
		(fp_line
			(start -0.51435 -0.2794)
			(end -0.51435 0.2794)
			(stroke
				(width 0.1)
				(type default)
			)
			(layer "B.Fab")
		)
		(fp_line
			(start 0.51435 0.2794)
			(end 0.51435 -0.2794)
			(stroke
				(width 0.1)
				(type default)
			)
			(layer "B.Fab")
		)
		(fp_line
			(start -0.51435 0.2794)
			(end 0.51435 0.2794)
			(stroke
				(width 0.1)
				(type default)
			)
			(layer "B.Fab")
		)
		(pad "1" smd circle
			(at 0.40005 0 270)
			(size 0 0)
			(layers "B.Cu" "B.Mask" "B.Paste")
			(net "P3V3_VCC_FPGA_CORE")
		)
		(pad "2" smd circle
			(at -0.40005 0 270)
			(size 0 0)
			(layers "B.Cu" "B.Mask" "B.Paste")
			(net "GND")
		)
		(zone
			(layer "B.Cu")
			(hatch none 0.5)
			(connect_pads
				(clearance 0)
			)
			(min_thickness 0.25)
			(keepout
				(tracks not_allowed)
				(vias allowed)
				(pads allowed)
				(copperpour not_allowed)
				(footprints allowed)
			)
			(placement
				(enabled no)
				(sheetname "")
			)
			(fill
				(thermal_gap 0.5)
				(thermal_bridge_width 0.5)
				(island_removal_mode 0)
			)
			(polygon
				(pts
					(xy 342.981026 -220.57741) (xy 343.039192 -220.48597) (xy 343.039192 -220.28658) (xy 342.981026 -220.19641)
					(xy 342.805766 -220.19641) (xy 342.747346 -220.28658) (xy 342.747346 -220.48597) (xy 342.805512 -220.57741)
				)
			)
		)
	)
	(footprint ""
		(layer "B.Cu")
		(at 425.841922 -97.005648 180)
		(property "Reference" "R369"
			(at 0 0 0)
			(layer "B.SilkS")
			(hide yes)
			(effects
				(font
					(size 1.27 1.27)
				)
				(justify mirror)
			)
		)
		(property "Value" ""
			(at 0 0 0)
			(layer "B.Fab")
			(effects
				(font
					(size 1.27 1.27)
				)
				(justify mirror)
			)
		)
		(duplicate_pad_numbers_are_jumpers no)
		(fp_line
			(start 0.7874 0.4064)
			(end 0.7874 -0.4064)
			(stroke
				(width 0.1524)
				(type default)
			)
			(layer "B.SilkS")
		)
		(fp_line
			(start 0.7874 -0.4064)
			(end -0.7874 -0.4064)
			(stroke
				(width 0.1524)
				(type default)
			)
			(layer "B.SilkS")
		)
		(fp_line
			(start -0.7874 0.4064)
			(end 0.7874 0.4064)
			(stroke
				(width 0.1524)
				(type default)
			)
			(layer "B.SilkS")
		)
		(fp_line
			(start -0.7874 -0.4064)
			(end -0.7874 0.4064)
			(stroke
				(width 0.1524)
				(type default)
			)
			(layer "B.SilkS")
		)
		(fp_line
			(start 0.67945 0.3048)
			(end 0.67945 -0.305054)
			(stroke
				(width 0.1)
				(type default)
			)
			(layer "B.Fab")
		)
		(fp_line
			(start 0.67945 -0.305054)
			(end 0.12065 -0.305054)
			(stroke
				(width 0.1)
				(type default)
			)
			(layer "B.Fab")
		)
		(fp_line
			(start 0.12065 0.3048)
			(end 0.67945 0.3048)
			(stroke
				(width 0.1)
				(type default)
			)
			(layer "B.Fab")
		)
		(fp_line
			(start 0.12065 0.2794)
			(end 0.12065 0.3048)
			(stroke
				(width 0.1)
				(type default)
			)
			(layer "B.Fab")
		)
		(fp_line
			(start 0.12065 -0.2794)
			(end -0.12065 -0.2794)
			(stroke
				(width 0.1)
				(type default)
			)
			(layer "B.Fab")
		)
		(fp_line
			(start 0.12065 -0.305054)
			(end 0.12065 -0.2794)
			(stroke
				(width 0.1)
				(type default)
			)
			(layer "B.Fab")
		)
		(fp_line
			(start -0.120396 0.3048)
			(end -0.120396 0.2794)
			(stroke
				(width 0.1)
				(type default)
			)
			(layer "B.Fab")
		)
		(fp_line
			(start -0.120396 0.2794)
			(end 0.12065 0.2794)
			(stroke
				(width 0.1)
				(type default)
			)
			(layer "B.Fab")
		)
		(fp_line
			(start -0.12065 -0.2794)
			(end -0.12065 -0.3048)
			(stroke
				(width 0.1)
				(type default)
			)
			(layer "B.Fab")
		)
		(fp_line
			(start -0.12065 -0.3048)
			(end -0.67945 -0.3048)
			(stroke
				(width 0.1)
				(type default)
			)
			(layer "B.Fab")
		)
		(fp_line
			(start -0.67945 0.3048)
			(end -0.120396 0.3048)
			(stroke
				(width 0.1)
				(type default)
			)
			(layer "B.Fab")
		)
		(fp_line
			(start -0.67945 -0.3048)
			(end -0.67945 0.3048)
			(stroke
				(width 0.1)
				(type default)
			)
			(layer "B.Fab")
		)
		(pad "1" smd circle
			(at 0.40005 0)
			(size 0 0)
			(layers "B.Cu" "B.Mask" "B.Paste")
			(net "NIC7_DATA_IN")
		)
		(pad "2" smd circle
			(at -0.40005 0)
			(size 0 0)
			(layers "B.Cu" "B.Mask" "B.Paste")
			(net "P3V3_NIC7")
		)
	)
	(footprint ""
		(layer "B.Cu")
		(at 59.087004 -157.429962)
		(property "Reference" "U11"
			(at 0.846074 -2.258314 0)
			(unlocked yes)
			(layer "B.SilkS")
			(effects
				(font
					(size 0.7874 0.5842)
					(thickness 0.1524)
				)
				(justify left mirror)
			)
		)
		(property "Value" ""
			(at 0 0 0)
			(layer "B.Fab")
			(effects
				(font
					(size 1.27 1.27)
				)
				(justify mirror)
			)
		)
		(duplicate_pad_numbers_are_jumpers no)
		(fp_line
			(start -2.0574 -1.651)
			(end -2.0574 1.651)
			(stroke
				(width 0.1524)
				(type default)
			)
			(layer "B.SilkS")
		)
		(fp_line
			(start -2.0574 1.651)
			(end 2.0574 1.651)
			(stroke
				(width 0.1524)
				(type default)
			)
			(layer "B.SilkS")
		)
		(fp_line
			(start -0.381 -1.651)
			(end -2.0574 -1.651)
			(stroke
				(width 0.1524)
				(type default)
			)
			(layer "B.SilkS")
		)
		(fp_line
			(start 0 -1.016)
			(end -0.381 -1.651)
			(stroke
				(width 0.1524)
				(type default)
			)
			(layer "B.SilkS")
		)
		(fp_line
			(start 0.381 -1.651)
			(end 0 -1.016)
			(stroke
				(width 0.1524)
				(type default)
			)
			(layer "B.SilkS")
		)
		(fp_line
			(start 2.0574 -1.651)
			(end 0.381 -1.651)
			(stroke
				(width 0.1524)
				(type default)
			)
			(layer "B.SilkS")
		)
		(fp_line
			(start 2.0574 1.651)
			(end 2.0574 -1.651)
			(stroke
				(width 0.1524)
				(type default)
			)
			(layer "B.SilkS")
		)
		(fp_poly
			(pts
				(xy 2.71272 -0.719328) (xy 2.71272 -1.344168) (xy 2.159 -1.016)
			)
			(stroke
				(width 0)
				(type default)
			)
			(fill yes)
			(layer "B.SilkS")
		)
		(fp_line
			(start -1.599946 -1.199896)
			(end -1.599946 1.199896)
			(stroke
				(width 0.1)
				(type default)
			)
			(layer "B.Fab")
		)
		(fp_line
			(start -1.599946 1.199896)
			(end -0.899922 1.199896)
			(stroke
				(width 0.1)
				(type default)
			)
			(layer "B.Fab")
		)
		(fp_line
			(start -0.899922 -1.549908)
			(end -0.899922 -1.199896)
			(stroke
				(width 0.1)
				(type default)
			)
			(layer "B.Fab")
		)
		(fp_line
			(start -0.899922 -1.199896)
			(end -1.599946 -1.199896)
			(stroke
				(width 0.1)
				(type default)
			)
			(layer "B.Fab")
		)
		(fp_line
			(start -0.899922 1.199896)
			(end -0.899922 1.549908)
			(stroke
				(width 0.1)
				(type default)
			)
			(layer "B.Fab")
		)
		(fp_line
			(start -0.899922 1.549908)
			(end 0.899922 1.549908)
			(stroke
				(width 0.1)
				(type default)
			)
			(layer "B.Fab")
		)
		(fp_line
			(start 0.899922 -1.549908)
			(end -0.899922 -1.549908)
			(stroke
				(width 0.1)
				(type default)
			)
			(layer "B.Fab")
		)
		(fp_line
			(start 0.899922 -1.199896)
			(end 0.899922 -1.549908)
			(stroke
				(width 0.1)
				(type default)
			)
			(layer "B.Fab")
		)
		(fp_line
			(start 0.899922 1.199896)
			(end 1.599946 1.199896)
			(stroke
				(width 0.1)
				(type default)
			)
			(layer "B.Fab")
		)
		(fp_line
			(start 0.899922 1.549908)
			(end 0.899922 1.199896)
			(stroke
				(width 0.1)
				(type default)
			)
			(layer "B.Fab")
		)
		(fp_line
			(start 1.599946 -1.199896)
			(end 0.899922 -1.199896)
			(stroke
				(width 0.1)
				(type default)
			)
			(layer "B.Fab")
		)
		(fp_line
			(start 1.599946 1.199896)
			(end 1.599946 -1.199896)
			(stroke
				(width 0.1)
				(type default)
			)
			(layer "B.Fab")
		)
		(fp_poly
			(pts
				(xy 2.71272 -0.719328) (xy 2.71272 -1.344168) (xy 2.159 -1.016)
			)
			(stroke
				(width 0)
				(type default)
			)
			(fill yes)
			(layer "B.Fab")
		)
		(pad "1" smd rect
			(at 1.225042 -0.94996 270)
			(size 0.5588 1.3462)
			(layers "B.Cu" "B.Mask" "B.Paste")
			(net "HP_NIC0_PWRGD_R")
		)
		(pad "2" smd rect
			(at 1.225042 0 270)
			(size 0.5588 1.3462)
			(layers "B.Cu" "B.Mask" "B.Paste")
			(net "RST_NIC0_PERST_R_N")
		)
		(pad "3" smd rect
			(at 1.225042 0.94996 270)
			(size 0.5588 1.3462)
			(layers "B.Cu" "B.Mask" "B.Paste")
			(net "GND")
		)
		(pad "4" smd rect
			(at -1.225042 0.94996 270)
			(size 0.5588 1.3462)
			(layers "B.Cu" "B.Mask" "B.Paste")
			(net "RST_HP_NIC0_N")
		)
		(pad "5" smd rect
			(at -1.225042 -0.94996 270)
			(size 0.5588 1.3462)
			(layers "B.Cu" "B.Mask" "B.Paste")
			(net "P3V3_AUX")
		)
	)
)
